FILE_TYPE = MACRO_DRAWING;
SET COLOR_WIRE YELLOW;
SET COLOR_PROP MONO;
SET COLOR_DOT WHITE;
SET COLOR_ARC YELLOW;
SET COLOR_BODY GREEN;
SET COLOR_NOTE MONO;
SET PROP_DISPLAY VALUE;
SET PAGE_NUMBER P15;
FORCEADD INTEL_CORP_BPAGE..1
(25 2025);
FORCEPROP 1 LAST CUSTOM_TXT_CDS <CURRENT_DESIGN_SHEET> OF <TOTAL_DESIGN_SHEETS>
J 0
(-475 2050);
PAINT GREEN (-475 2050);
FORCEPROP 1 LAST CUSTOM_TXT_CDS <CON_LAST_MODIFIED>
J 0
(-1900 2375);
PAINT GREEN (-1900 2375);
FORCEPROP 2 LAST CUSTOM_TXT_CDS <XR_PAGE_TITLE>
J 0
(-7865 7275);
DISPLAY 0.638298 (-7865 7275);
PAINT PINK (-7865 7275);
DISPLAY INVISIBLE (-7865 7275);
FORCEPROP 1 LAST SCH_REV 2.420
J 0
(-225 2175);
DISPLAY 0.978723 (-225 2175);
PAINT YELLOW (-225 2175);
FORCEPROP 1 LAST SCH_DEPT BESD
J 1
(-4425 2125);
DISPLAY 1.212766 (-4425 2125);
PAINT YELLOW (-4425 2125);
FORCEPROP 1 LAST SCH_NUMBER H4694802
J 0
(-1275 2175);
DISPLAY 1.212766 (-1275 2175);
PAINT YELLOW (-1275 2175);
FORCEPROP 1 LAST SCH_ADDRESS1 2200 Mission College Blvd.
J 0
(-3950 2150);
DISPLAY 0.617021 (-3950 2150);
PAINT GREEN (-3950 2150);
FORCEPROP 1 LAST SCH_ADDRESS2 P.O. BOX 58119
J 0
(-3950 2100);
DISPLAY 0.617021 (-3950 2100);
PAINT GREEN (-3950 2100);
FORCEPROP 1 LAST SCH_ADDRESS3 Santa Clara, CA 95052-8119
J 0
(-3950 2050);
DISPLAY 0.617021 (-3950 2050);
PAINT GREEN (-3950 2050);
FORCEPROP 1 LAST SCH_TITLE PWRGD/RESET
J 0
(-7925 2075);
DISPLAY 1.212766 (-7925 2075);
PAINT ORANGE (-7925 2075);
FORCEPROP 2 LAST PAGE_BORDER TRUE
J 0
(-7865 7275);
DISPLAY 0.638298 (-7865 7275);
PAINT PINK (-7865 7275);
DISPLAY INVISIBLE (-7865 7275);
FORCEPROP 2 LAST CDS_LIB mstr_symbols
J 0
(25 2025);
PAINT MONO (25 2025);
DISPLAY INVISIBLE (25 2025);
FORCEPROP 1 LAST COMMENT_BODY TRUE
J 0
(37 2037);
DISPLAY 0.468085 (37 2037);
PAINT GREEN (37 2037);
DISPLAY INVISIBLE (37 2037);
FORCEPROP 1 LAST CDS_CON_LAST_MODIFIED Tue Dec 01 11:47:58 2015
J 0
(-1400 2350);
PAINT ORANGE (-1400 2350);
DISPLAY INVISIBLE (-1400 2350);
FORCEPROP 2 LAST CDS_XR_PAGE_TITLE CR-15 : @BASEBOARD_FAB2_LIB.BASEBOARD_FAB2(SCH_1):PAGE15
J 0
(-7865 7275);
DISPLAY 0.638298 (-7865 7275);
PAINT PINK (-7865 7275);
DISPLAY INVISIBLE (-7865 7275);
QUIT
